# BASEBOARD_FAB2 (Tioga Pass) — schematic netlist excerpt (pin names and nets, part order shuffled) for the footprints in the layout excerpt that follows; sources: Cadence DE-HDL packaged netlist, KiCad conversion of Wiwynn_Tioga_Pass_MB.brd

R9U1  RES  0.0 5% CHIP  pkg 0402  page 224 : A = VR_PVDDQ_GHJ_PH1_VCIN ; B = P5V_STBY
R771  RES  0.0 5% CHIP  pkg 0402  page 244 : A = P3E_CPU0_PE1_PCH_RXN<13> ; B = P3E_CPU0_PE1_PCH_CON_RXN<13>
R7P10  RES  49.9 1% CHIP  pkg 0402  page 55 : A = A_CPU1_PE012_RBIAS ; B = GND

(kicad_pcb
	(version 20260206)
	(generator "pcbnew")
	(generator_version "10.0")
	(general
		(thickness 1.6)
		(legacy_teardrops no)
	)
	(paper "A4")
	(title_block
		(title "Wiwynn_Tioga_Pass_MB.brd")
		(comment 1 "Tioga Pass / footprints 3447-3449 of 4770")
	)
	(layers
		(0 "F.Cu" signal "TOP")
		(4 "In1.Cu" signal "L2GND")
		(6 "In2.Cu" signal "L3")
		(8 "In3.Cu" signal "L4GND")
		(10 "In4.Cu" signal "L5")
		(12 "In5.Cu" signal "L6GND")
		(14 "In6.Cu" signal "L7VCC")
		(16 "In7.Cu" signal "L8VCC")
		(18 "In8.Cu" signal "L9GND")
		(20 "In9.Cu" signal "L10")
		(22 "In10.Cu" signal "L11GND")
		(24 "In11.Cu" signal "L12")
		(26 "In12.Cu" signal "L13GND")
		(2 "B.Cu" signal "BOTTOM")
		(9 "F.Adhes" user "F.Adhesive")
		(11 "B.Adhes" user "B.Adhesive")
		(13 "F.Paste" user "Package Geometry/Pastemask Top")
		(15 "B.Paste" user "Package Geometry/Pastemask Bottom")
		(5 "F.SilkS" user "Ref Des/Silkscreen Top")
		(7 "B.SilkS" user "Ref Des/Silkscreen Bottom")
		(1 "F.Mask" user "Board Geometry/Soldermask Top")
		(3 "B.Mask" user "Board Geometry/Soldermask Bottom")
		(17 "Dwgs.User" user "User.Drawings")
		(19 "Cmts.User" user "User.Comments")
		(21 "Eco1.User" user "User.Eco1")
		(23 "Eco2.User" user "User.Eco2")
		(25 "Edge.Cuts" user "Board Geometry/Outline")
		(27 "Margin" user)
		(31 "F.CrtYd" user "Package Geometry/Place Bound Top")
		(29 "B.CrtYd" user "Package Geometry/Place Bound Bottom")
		(35 "F.Fab" user "Ref Des/Assembly Top")
		(33 "B.Fab" user "Ref Des/Assembly Bottom")
	)
	(footprint ""
		(layer "B.Cu")
		(at 117.221 -77.978 -90)
		(property "Reference" "R7P10"
			(at 0 0 90)
			(layer "B.SilkS")
			(hide yes)
			(effects
				(font
					(size 1.27 1.27)
				)
				(justify mirror)
			)
		)
		(property "Value" ""
			(at 0 0 90)
			(layer "B.Fab")
			(effects
				(font
					(size 1.27 1.27)
				)
				(justify mirror)
			)
		)
		(duplicate_pad_numbers_are_jumpers no)
		(fp_poly
			(pts
				(xy 0.2794 -0.1016) (xy -0.2794 -0.1016) (xy -0.2794 0.9906) (xy 0.2794 0.9906)
			)
			(stroke
				(width 0)
				(type default)
			)
			(fill no)
			(layer "B.CrtYd")
		)
		(fp_line
			(start -0.2794 0.9906)
			(end -0.2794 -0.1016)
			(stroke
				(width 0.1)
				(type default)
			)
			(layer "B.Fab")
		)
		(fp_line
			(start 0.2794 0.9906)
			(end -0.2794 0.9906)
			(stroke
				(width 0.1)
				(type default)
			)
			(layer "B.Fab")
		)
		(fp_line
			(start -0.2794 -0.1016)
			(end 0.2794 -0.1016)
			(stroke
				(width 0.1)
				(type default)
			)
			(layer "B.Fab")
		)
		(fp_line
			(start 0.2794 -0.1016)
			(end 0.2794 0.9906)
			(stroke
				(width 0.1)
				(type default)
			)
			(layer "B.Fab")
		)
		(pad "1" smd rect
			(at 0 0 90)
			(size 0.508 0.508)
			(layers "B.Cu" "B.Mask" "B.Paste")
			(net "A_CPU1_PE012_RBIAS")
		)
		(pad "2" smd rect
			(at 0 0.889 90)
			(size 0.508 0.508)
			(layers "B.Cu" "B.Mask" "B.Paste")
			(net "GND")
		)
		(zone
			(layer "B.Cu")
			(hatch none 0.5)
			(connect_pads
				(clearance 0)
			)
			(min_thickness 0.25)
			(keepout
				(tracks not_allowed)
				(vias allowed)
				(pads allowed)
				(copperpour not_allowed)
				(footprints allowed)
			)
			(placement
				(enabled no)
				(sheetname "")
			)
			(fill
				(thermal_gap 0.5)
				(thermal_bridge_width 0.5)
				(island_removal_mode 0)
			)
			(polygon
				(pts
					(xy 116.586 -77.724) (xy 116.586 -78.232) (xy 116.967 -78.232) (xy 116.967 -77.724)
				)
			)
		)
		(zone
			(layer "B.Cu")
			(hatch none 0.5)
			(connect_pads
				(clearance 0)
			)
			(min_thickness 0.25)
			(keepout
				(tracks allowed)
				(vias not_allowed)
				(pads allowed)
				(copperpour not_allowed)
				(footprints allowed)
			)
			(placement
				(enabled no)
				(sheetname "")
			)
			(fill
				(thermal_gap 0.5)
				(thermal_bridge_width 0.5)
				(island_removal_mode 0)
			)
			(polygon
				(pts
					(xy 116.967 -77.724) (xy 116.967 -78.232) (xy 116.586 -78.232) (xy 116.586 -77.724)
				)
			)
		)
	)
	(footprint ""
		(layer "B.Cu")
		(at 348.600014 -122.459242 -90)
		(property "Reference" "R771"
			(at 0.8382 -0.67818 270)
			(unlocked yes)
			(layer "B.SilkS")
			(effects
				(font
					(size 0.4064 0.254)
					(thickness 0.1524)
				)
				(justify left mirror)
			)
		)
		(property "Value" ""
			(at 0 0 90)
			(layer "B.Fab")
			(effects
				(font
					(size 1.27 1.27)
				)
				(justify mirror)
			)
		)
		(duplicate_pad_numbers_are_jumpers no)
		(fp_poly
			(pts
				(xy 0.2794 -0.1016) (xy -0.2794 -0.1016) (xy -0.2794 0.9906) (xy 0.2794 0.9906)
			)
			(stroke
				(width 0)
				(type default)
			)
			(fill no)
			(layer "B.CrtYd")
		)
		(fp_line
			(start -0.2794 0.9906)
			(end -0.2794 -0.1016)
			(stroke
				(width 0.1)
				(type default)
			)
			(layer "B.Fab")
		)
		(fp_line
			(start 0.2794 0.9906)
			(end -0.2794 0.9906)
			(stroke
				(width 0.1)
				(type default)
			)
			(layer "B.Fab")
		)
		(fp_line
			(start -0.2794 -0.1016)
			(end 0.2794 -0.1016)
			(stroke
				(width 0.1)
				(type default)
			)
			(layer "B.Fab")
		)
		(fp_line
			(start 0.2794 -0.1016)
			(end 0.2794 0.9906)
			(stroke
				(width 0.1)
				(type default)
			)
			(layer "B.Fab")
		)
		(pad "1" smd rect
			(at 0 0 90)
			(size 0.508 0.508)
			(layers "B.Cu" "B.Mask" "B.Paste")
			(net "P3E_CPU0_PE1_PCH_RXN<13>")
		)
		(pad "2" smd rect
			(at 0 0.889 90)
			(size 0.508 0.508)
			(layers "B.Cu" "B.Mask" "B.Paste")
			(net "P3E_CPU0_PE1_PCH_CON_RXN<13>")
		)
		(zone
			(layer "B.Cu")
			(hatch none 0.5)
			(connect_pads
				(clearance 0)
			)
			(min_thickness 0.25)
			(keepout
				(tracks not_allowed)
				(vias allowed)
				(pads allowed)
				(copperpour not_allowed)
				(footprints allowed)
			)
			(placement
				(enabled no)
				(sheetname "")
			)
			(fill
				(thermal_gap 0.5)
				(thermal_bridge_width 0.5)
				(island_removal_mode 0)
			)
			(polygon
				(pts
					(xy 347.965014 -122.205242) (xy 347.965014 -122.713242) (xy 348.346014 -122.713242) (xy 348.346014 -122.205242)
				)
			)
		)
		(zone
			(layer "B.Cu")
			(hatch none 0.5)
			(connect_pads
				(clearance 0)
			)
			(min_thickness 0.25)
			(keepout
				(tracks allowed)
				(vias not_allowed)
				(pads allowed)
				(copperpour not_allowed)
				(footprints allowed)
			)
			(placement
				(enabled no)
				(sheetname "")
			)
			(fill
				(thermal_gap 0.5)
				(thermal_bridge_width 0.5)
				(island_removal_mode 0)
			)
			(polygon
				(pts
					(xy 348.346014 -122.205242) (xy 348.346014 -122.713242) (xy 347.965014 -122.713242) (xy 347.965014 -122.205242)
				)
			)
		)
	)
	(footprint ""
		(layer "B.Cu")
		(at 3.04292 -5.41782 90)
		(property "Reference" "R9U1"
			(at 0 0 90)
			(layer "B.SilkS")
			(hide yes)
			(effects
				(font
					(size 1.27 1.27)
				)
				(justify mirror)
			)
		)
		(property "Value" ""
			(at 0 0 90)
			(layer "B.Fab")
			(effects
				(font
					(size 1.27 1.27)
				)
				(justify mirror)
			)
		)
		(duplicate_pad_numbers_are_jumpers no)
		(fp_rect
			(start -0.2794 -0.1016)
			(end 0.2794 0.9906)
			(stroke
				(width 0)
				(type default)
			)
			(fill no)
			(layer "B.CrtYd")
		)
		(fp_line
			(start 0.2794 -0.1016)
			(end 0.2794 0.9906)
			(stroke
				(width 0.1)
				(type default)
			)
			(layer "B.Fab")
		)
		(fp_line
			(start -0.2794 -0.1016)
			(end 0.2794 -0.1016)
			(stroke
				(width 0.1)
				(type default)
			)
			(layer "B.Fab")
		)
		(fp_line
			(start 0.2794 0.9906)
			(end -0.2794 0.9906)
			(stroke
				(width 0.1)
				(type default)
			)
			(layer "B.Fab")
		)
		(fp_line
			(start -0.2794 0.9906)
			(end -0.2794 -0.1016)
			(stroke
				(width 0.1)
				(type default)
			)
			(layer "B.Fab")
		)
		(pad "1" smd rect
			(at 0 0 270)
			(size 0.508 0.508)
			(layers "B.Cu" "B.Mask" "B.Paste")
			(net "VR_PVDDQ_GHJ_PH1_VCIN")
		)
		(pad "2" smd rect
			(at 0 0.889 270)
			(size 0.508 0.508)
			(layers "B.Cu" "B.Mask" "B.Paste")
			(net "P5V_STBY")
		)
		(zone
			(layer "B.Cu")
			(hatch none 0.5)
			(connect_pads
				(clearance 0)
			)
			(min_thickness 0.25)
			(keepout
				(tracks allowed)
				(vias not_allowed)
				(pads allowed)
				(copperpour not_allowed)
				(footprints allowed)
			)
			(placement
				(enabled no)
				(sheetname "")
			)
			(fill
				(thermal_gap 0.5)
				(thermal_bridge_width 0.5)
				(island_removal_mode 0)
			)
			(polygon
				(pts
					(xy 3.29692 -5.16382) (xy 3.67792 -5.16382) (xy 3.67792 -5.67182) (xy 3.29692 -5.67182)
				)
			)
		)
		(zone
			(layer "B.Cu")
			(hatch none 0.5)
			(connect_pads
				(clearance 0)
			)
			(min_thickness 0.25)
			(keepout
				(tracks not_allowed)
				(vias allowed)
				(pads allowed)
				(copperpour not_allowed)
				(footprints allowed)
			)
			(placement
				(enabled no)
				(sheetname "")
			)
			(fill
				(thermal_gap 0.5)
				(thermal_bridge_width 0.5)
				(island_removal_mode 0)
			)
			(polygon
				(pts
					(xy 3.29692 -5.16382) (xy 3.67792 -5.16382) (xy 3.67792 -5.67182) (xy 3.29692 -5.67182)
				)
			)
		)
	)
)
